# T6G (Grand Teton) — schematic netlist excerpt (pin names and nets, part order shuffled) for the footprints in the layout excerpt that follows; sources: Cadence DE-HDL packaged netlist, KiCad conversion of 04192023_DAF0TMB3IC0_F0TG_MB_C_brd_V02_OCP.brd

R4536  Q_RES  0 5% CHIP  pkg 0402LF  page 28 : A = CLK_100M_CPU0_CLK01_R_DN ; B = CLK_100M_CPU0_CLK01_DN
C214  Q_CAP  3.9P 50V 0.1P NPO  pkg C0402  page 28 : A = XTAL_CPU0_X48M_X2_R ; B = GND
C491  Q_CAP  1UF 4V 20% X6S  pkg 0201  page 356 : A = P0V9_CPU1_RT3_2A ; B = GND

(kicad_pcb
	(version 20260206)
	(generator "pcbnew")
	(generator_version "10.0")
	(general
		(thickness 1.6)
		(legacy_teardrops no)
	)
	(paper "A4")
	(title_block
		(title "04192023_DAF0TMB3IC0_F0TG_MB_C_brd_V02_OCP.brd")
		(comment 1 "Grand Teton / footprints 5735-5737 of 8354")
	)
	(layers
		(0 "F.Cu" signal "TOP")
		(4 "In1.Cu" signal "GND")
		(6 "In2.Cu" signal "IN1")
		(8 "In3.Cu" signal "GND1")
		(10 "In4.Cu" signal "IN2")
		(12 "In5.Cu" signal "GND2")
		(14 "In6.Cu" signal "IN3")
		(16 "In7.Cu" signal "GND3")
		(18 "In8.Cu" signal "VCC")
		(20 "In9.Cu" signal "VCC1")
		(22 "In10.Cu" signal "GND4")
		(24 "In11.Cu" signal "IN4")
		(26 "In12.Cu" signal "GND5")
		(28 "In13.Cu" signal "IN5")
		(30 "In14.Cu" signal "GND6")
		(32 "In15.Cu" signal "IN6")
		(34 "In16.Cu" signal "GND7")
		(2 "B.Cu" signal "BOTTOM")
		(9 "F.Adhes" user "F.Adhesive")
		(11 "B.Adhes" user "B.Adhesive")
		(13 "F.Paste" user "Package Geometry/Pastemask Top")
		(15 "B.Paste" user "Package Geometry/Pastemask Bottom")
		(5 "F.SilkS" user "Ref Des/Silkscreen Top")
		(7 "B.SilkS" user "Ref Des/Silkscreen Bottom")
		(1 "F.Mask" user "Board Geometry/Soldermask Top")
		(3 "B.Mask" user "Board Geometry/Soldermask Bottom")
		(17 "Dwgs.User" user "User.Drawings")
		(19 "Cmts.User" user "User.Comments")
		(21 "Eco1.User" user "User.Eco1")
		(23 "Eco2.User" user "User.Eco2")
		(25 "Edge.Cuts" user "Board Geometry/Outline")
		(27 "Margin" user)
		(31 "F.CrtYd" user "Package Geometry/Place Bound Top")
		(29 "B.CrtYd" user "Package Geometry/Place Bound Bottom")
		(35 "F.Fab" user "Ref Des/Assembly Top")
		(33 "B.Fab" user "Ref Des/Assembly Bottom")
	)
	(footprint ""
		(layer "B.Cu")
		(at 371.134386 -214.523828 90)
		(property "Reference" "R4536"
			(at 0 0 90)
			(layer "B.SilkS")
			(hide yes)
			(effects
				(font
					(size 1.27 1.27)
				)
				(justify mirror)
			)
		)
		(property "Value" ""
			(at 0 0 90)
			(layer "B.Fab")
			(effects
				(font
					(size 1.27 1.27)
				)
				(justify mirror)
			)
		)
		(duplicate_pad_numbers_are_jumpers no)
		(fp_line
			(start 0.7874 -0.4064)
			(end -0.7874 -0.4064)
			(stroke
				(width 0.1524)
				(type default)
			)
			(layer "B.SilkS")
		)
		(fp_line
			(start -0.7874 -0.4064)
			(end -0.7874 -0.014986)
			(stroke
				(width 0.1524)
				(type default)
			)
			(layer "B.SilkS")
		)
		(fp_line
			(start 0.7874 -0.040386)
			(end 0.7874 -0.4064)
			(stroke
				(width 0.1524)
				(type default)
			)
			(layer "B.SilkS")
		)
		(fp_line
			(start -0.351028 0.4064)
			(end 0.512572 0.4064)
			(stroke
				(width 0.1524)
				(type default)
			)
			(layer "B.SilkS")
		)
		(fp_line
			(start 0.67945 -0.305054)
			(end 0.12065 -0.305054)
			(stroke
				(width 0.1)
				(type default)
			)
			(layer "B.Fab")
		)
		(fp_line
			(start 0.12065 -0.305054)
			(end 0.12065 -0.2794)
			(stroke
				(width 0.1)
				(type default)
			)
			(layer "B.Fab")
		)
		(fp_line
			(start -0.12065 -0.3048)
			(end -0.67945 -0.3048)
			(stroke
				(width 0.1)
				(type default)
			)
			(layer "B.Fab")
		)
		(fp_line
			(start -0.67945 -0.3048)
			(end -0.67945 0.3048)
			(stroke
				(width 0.1)
				(type default)
			)
			(layer "B.Fab")
		)
		(fp_line
			(start 0.12065 -0.2794)
			(end -0.12065 -0.2794)
			(stroke
				(width 0.1)
				(type default)
			)
			(layer "B.Fab")
		)
		(fp_line
			(start -0.12065 -0.2794)
			(end -0.12065 -0.3048)
			(stroke
				(width 0.1)
				(type default)
			)
			(layer "B.Fab")
		)
		(fp_line
			(start 0.12065 0.2794)
			(end 0.12065 0.3048)
			(stroke
				(width 0.1)
				(type default)
			)
			(layer "B.Fab")
		)
		(fp_line
			(start -0.120396 0.2794)
			(end 0.12065 0.2794)
			(stroke
				(width 0.1)
				(type default)
			)
			(layer "B.Fab")
		)
		(fp_line
			(start 0.67945 0.3048)
			(end 0.67945 -0.305054)
			(stroke
				(width 0.1)
				(type default)
			)
			(layer "B.Fab")
		)
		(fp_line
			(start 0.12065 0.3048)
			(end 0.67945 0.3048)
			(stroke
				(width 0.1)
				(type default)
			)
			(layer "B.Fab")
		)
		(fp_line
			(start -0.120396 0.3048)
			(end -0.120396 0.2794)
			(stroke
				(width 0.1)
				(type default)
			)
			(layer "B.Fab")
		)
		(fp_line
			(start -0.67945 0.3048)
			(end -0.120396 0.3048)
			(stroke
				(width 0.1)
				(type default)
			)
			(layer "B.Fab")
		)
		(pad "1" smd circle
			(at 0.40005 0 270)
			(size 0 0)
			(layers "B.Cu" "B.Mask" "B.Paste")
			(net "CLK_100M_CPU0_CLK01_R_DN")
		)
		(pad "2" smd circle
			(at -0.40005 0 270)
			(size 0 0)
			(layers "B.Cu" "B.Mask" "B.Paste")
			(net "CLK_100M_CPU0_CLK01_DN")
		)
	)
	(footprint ""
		(layer "B.Cu")
		(at 115.678458 -386.766562 90)
		(property "Reference" "C491"
			(at 0 0 90)
			(layer "B.SilkS")
			(hide yes)
			(effects
				(font
					(size 1.27 1.27)
				)
				(justify mirror)
			)
		)
		(property "Value" ""
			(at 0 0 90)
			(layer "B.Fab")
			(effects
				(font
					(size 1.27 1.27)
				)
				(justify mirror)
			)
		)
		(duplicate_pad_numbers_are_jumpers no)
		(fp_line
			(start 0.299974 -0.150114)
			(end -0.299974 -0.150114)
			(stroke
				(width 0.1)
				(type default)
			)
			(layer "B.Fab")
		)
		(fp_line
			(start -0.299974 -0.150114)
			(end -0.299974 0.150114)
			(stroke
				(width 0.1)
				(type default)
			)
			(layer "B.Fab")
		)
		(fp_line
			(start 0.299974 0.150114)
			(end 0.299974 -0.150114)
			(stroke
				(width 0.1)
				(type default)
			)
			(layer "B.Fab")
		)
		(fp_line
			(start -0.299974 0.150114)
			(end 0.299974 0.150114)
			(stroke
				(width 0.1)
				(type default)
			)
			(layer "B.Fab")
		)
		(pad "1" smd rect
			(at 0.2667 0 270)
			(size 0.3048 0.381)
			(layers "B.Cu" "B.Mask" "B.Paste")
			(net "P0V9_CPU1_RT3_2A")
		)
		(pad "2" smd rect
			(at -0.2667 0 270)
			(size 0.3048 0.381)
			(layers "B.Cu" "B.Mask" "B.Paste")
			(net "GND")
		)
	)
	(footprint ""
		(layer "B.Cu")
		(at 397.830802 -314.366148 180)
		(property "Reference" "C214"
			(at 0 0 0)
			(layer "B.SilkS")
			(hide yes)
			(effects
				(font
					(size 1.27 1.27)
				)
				(justify mirror)
			)
		)
		(property "Value" ""
			(at 0 0 0)
			(layer "B.Fab")
			(effects
				(font
					(size 1.27 1.27)
				)
				(justify mirror)
			)
		)
		(duplicate_pad_numbers_are_jumpers no)
		(fp_line
			(start 0.7874 0.4064)
			(end 0.7874 -0.4064)
			(stroke
				(width 0.1524)
				(type default)
			)
			(layer "B.SilkS")
		)
		(fp_line
			(start 0.7874 -0.4064)
			(end -0.7874 -0.4064)
			(stroke
				(width 0.1524)
				(type default)
			)
			(layer "B.SilkS")
		)
		(fp_line
			(start -0.7874 0.4064)
			(end 0.7874 0.4064)
			(stroke
				(width 0.1524)
				(type default)
			)
			(layer "B.SilkS")
		)
		(fp_line
			(start -0.7874 -0.4064)
			(end -0.7874 0.4064)
			(stroke
				(width 0.1524)
				(type default)
			)
			(layer "B.SilkS")
		)
		(fp_line
			(start 0.67945 0.3048)
			(end 0.67945 -0.305054)
			(stroke
				(width 0.1)
				(type default)
			)
			(layer "B.Fab")
		)
		(fp_line
			(start 0.67945 -0.305054)
			(end 0.12065 -0.305054)
			(stroke
				(width 0.1)
				(type default)
			)
			(layer "B.Fab")
		)
		(fp_line
			(start 0.12065 0.3048)
			(end 0.67945 0.3048)
			(stroke
				(width 0.1)
				(type default)
			)
			(layer "B.Fab")
		)
		(fp_line
			(start 0.12065 0.2794)
			(end 0.12065 0.3048)
			(stroke
				(width 0.1)
				(type default)
			)
			(layer "B.Fab")
		)
		(fp_line
			(start 0.12065 -0.2794)
			(end -0.12065 -0.2794)
			(stroke
				(width 0.1)
				(type default)
			)
			(layer "B.Fab")
		)
		(fp_line
			(start 0.12065 -0.305054)
			(end 0.12065 -0.2794)
			(stroke
				(width 0.1)
				(type default)
			)
			(layer "B.Fab")
		)
		(fp_line
			(start -0.120396 0.3048)
			(end -0.120396 0.2794)
			(stroke
				(width 0.1)
				(type default)
			)
			(layer "B.Fab")
		)
		(fp_line
			(start -0.120396 0.2794)
			(end 0.12065 0.2794)
			(stroke
				(width 0.1)
				(type default)
			)
			(layer "B.Fab")
		)
		(fp_line
			(start -0.12065 -0.2794)
			(end -0.12065 -0.3048)
			(stroke
				(width 0.1)
				(type default)
			)
			(layer "B.Fab")
		)
		(fp_line
			(start -0.12065 -0.3048)
			(end -0.67945 -0.3048)
			(stroke
				(width 0.1)
				(type default)
			)
			(layer "B.Fab")
		)
		(fp_line
			(start -0.67945 0.3048)
			(end -0.120396 0.3048)
			(stroke
				(width 0.1)
				(type default)
			)
			(layer "B.Fab")
		)
		(fp_line
			(start -0.67945 -0.3048)
			(end -0.67945 0.3048)
			(stroke
				(width 0.1)
				(type default)
			)
			(layer "B.Fab")
		)
		(pad "1" smd circle
			(at 0.40005 0)
			(size 0 0)
			(layers "B.Cu" "B.Mask" "B.Paste")
			(net "XTAL_CPU0_X48M_X2_R")
		)
		(pad "2" smd circle
			(at -0.40005 0)
			(size 0 0)
			(layers "B.Cu" "B.Mask" "B.Paste")
			(net "GND")
		)
	)
)
